# BASEBOARD_FAB2 (Tioga Pass) — schematic netlist excerpt (pin names and nets, part order shuffled) for the footprints in the layout excerpt that follows; sources: Cadence DE-HDL packaged netlist, KiCad conversion of Wiwynn_Tioga_Pass_MB.brd

EU7B1  NCP3232L  IC  pkg SM  page 232
  SS  = VR_PVPP_DEF_SS
  FB  = VR_FB_PVPP_DEF
  COMP  = VR_COMP_PVPP_DEF_3
  ISET  = VR_PVPP_DEF_ISET
  AGND  = AGND_PVPP_DEF
  OTS  = AGND_PVPP_DEF
  PG  = PWRGD_PVPP_DEF_R
  VIN(0)  = VR_FET_SW_P12V_STBY_PVPP_DEF
  VIN(1)  = VR_FET_SW_P12V_STBY_PVPP_DEF
  VIN(2)  = VR_FET_SW_P12V_STBY_PVPP_DEF
  VIN(3)  = VR_FET_SW_P12V_STBY_PVPP_DEF
  VIN(4)  = VR_FET_SW_P12V_STBY_PVPP_DEF
  VIN(5)  = VR_FET_SW_P12V_STBY_PVPP_DEF
  VIN(6)  = VR_FET_SW_P12V_STBY_PVPP_DEF
  VSWH(0)  = VR_PVPP_DEF_PHASE
  PGND(0)  = GND
  PGND(1)  = GND
  PGND(2)  = GND
  PGND(3)  = GND
  PGND(4)  = GND
  PGND(5)  = GND
  PGND(6)  = GND
  PGND(7)  = GND
  PGND(8)  = GND
  PGND(9)  = GND
  PGND(10)  = GND
  PGND(11)  = GND
  PGND(12)  = GND
  VSWH(1)  = VR_PVPP_DEF_PHASE
  VSWH(2)  = VR_PVPP_DEF_PHASE
  VSWH(3)  = VR_PVPP_DEF_PHASE
  VSWH(4)  = VR_PVPP_DEF_PHASE
  VSWH(5)  = VR_PVPP_DEF_PHASE
  VSWH(6)  = VR_PVPP_DEF_PHASE
  VSW  = VR_PVPP_DEF_PHASE
  BST  = VR_PVPP_DEF_BOOT
  PGND(13)  = GND
  VB  = VR_VB_PVPP_DEF
  VCC  = VR_FET_SW_P12V_STBY_PVPP_DEF
  EN  = FM_PVPP_PVDDQ_CPU0_EN_DEF
  GND  = GND
  VIN(7)  = VR_FET_SW_P12V_STBY_PVPP_DEF
  VSWH(7)  = VR_PVPP_DEF_PHASE

(kicad_pcb
	(version 20260206)
	(generator "pcbnew")
	(generator_version "10.0")
	(general
		(thickness 1.6)
		(legacy_teardrops no)
	)
	(paper "A4")
	(title_block
		(title "Wiwynn_Tioga_Pass_MB.brd")
		(comment 1 "Tioga Pass / footprint 1728 of 4770 (EU7B1), pads 1-17 of 43")
	)
	(layers
		(0 "F.Cu" signal "TOP")
		(4 "In1.Cu" signal "L2GND")
		(6 "In2.Cu" signal "L3")
		(8 "In3.Cu" signal "L4GND")
		(10 "In4.Cu" signal "L5")
		(12 "In5.Cu" signal "L6GND")
		(14 "In6.Cu" signal "L7VCC")
		(16 "In7.Cu" signal "L8VCC")
		(18 "In8.Cu" signal "L9GND")
		(20 "In9.Cu" signal "L10")
		(22 "In10.Cu" signal "L11GND")
		(24 "In11.Cu" signal "L12")
		(26 "In12.Cu" signal "L13GND")
		(2 "B.Cu" signal "BOTTOM")
		(9 "F.Adhes" user "F.Adhesive")
		(11 "B.Adhes" user "B.Adhesive")
		(13 "F.Paste" user "Package Geometry/Pastemask Top")
		(15 "B.Paste" user "Package Geometry/Pastemask Bottom")
		(5 "F.SilkS" user "Ref Des/Silkscreen Top")
		(7 "B.SilkS" user "Ref Des/Silkscreen Bottom")
		(1 "F.Mask" user "Board Geometry/Soldermask Top")
		(3 "B.Mask" user "Board Geometry/Soldermask Bottom")
		(17 "Dwgs.User" user "User.Drawings")
		(19 "Cmts.User" user "User.Comments")
		(21 "Eco1.User" user "User.Eco1")
		(23 "Eco2.User" user "User.Eco2")
		(25 "Edge.Cuts" user "Board Geometry/Outline")
		(27 "Margin" user)
		(31 "F.CrtYd" user "Package Geometry/Place Bound Top")
		(29 "B.CrtYd" user "Package Geometry/Place Bound Bottom")
		(35 "F.Fab" user "Ref Des/Assembly Top")
		(33 "B.Fab" user "Ref Des/Assembly Bottom")
	)
	(footprint ""
		(layer "F.Cu")
		(at 344.043 -132.8547 90)
		(property "Reference" "EU7B1"
			(at 5.29463 -1.27 0)
			(unlocked yes)
			(layer "F.SilkS")
			(effects
				(font
					(size 0.7874 0.5842)
					(thickness 0.1524)
				)
				(justify left)
			)
		)
		(property "Value" ""
			(at 0 0 90)
			(layer "F.Fab")
			(effects
				(font
					(size 1.27 1.27)
				)
			)
		)
		(duplicate_pad_numbers_are_jumpers no)
		(pad "1" smd custom
			(at -2.8321 -2.249932 90)
			(size 0.06985 0.06985)
			(layers "F.Cu" "F.Mask" "F.Paste")
			(net "VR_PVPP_DEF_SS")
			(options
				(clearance outline)
				(anchor circle)
			)
			(primitives
				(gr_poly
					(pts
						(arc
							(start 0.2413 -0.1397)
							(mid 0.381 0)
							(end 0.2413 0.1397)
						)
						(xy -0.381 0.1397) (xy -0.381 -0.1397)
					)
					(width 0)
					(fill yes)
				)
			)
		)
		(pad "2" smd custom
			(at -2.8321 -1.75006 90)
			(size 0.06985 0.06985)
			(layers "F.Cu" "F.Mask" "F.Paste")
			(net "VR_FB_PVPP_DEF")
			(options
				(clearance outline)
				(anchor circle)
			)
			(primitives
				(gr_poly
					(pts
						(arc
							(start 0.2413 -0.1397)
							(mid 0.381 0)
							(end 0.2413 0.1397)
						)
						(xy -0.381 0.1397) (xy -0.381 -0.1397)
					)
					(width 0)
					(fill yes)
				)
			)
		)
		(pad "3" smd custom
			(at -2.8321 -1.249934 90)
			(size 0.06985 0.06985)
			(layers "F.Cu" "F.Mask" "F.Paste")
			(net "VR_COMP_PVPP_DEF_3")
			(options
				(clearance outline)
				(anchor circle)
			)
			(primitives
				(gr_poly
					(pts
						(arc
							(start 0.2413 -0.1397)
							(mid 0.381 0)
							(end 0.2413 0.1397)
						)
						(xy -0.381 0.1397) (xy -0.381 -0.1397)
					)
					(width 0)
					(fill yes)
				)
			)
		)
		(pad "4" smd custom
			(at -2.8321 -0.750062 90)
			(size 0.06985 0.06985)
			(layers "F.Cu" "F.Mask" "F.Paste")
			(net "VR_PVPP_DEF_ISET")
			(options
				(clearance outline)
				(anchor circle)
			)
			(primitives
				(gr_poly
					(pts
						(arc
							(start 0.2413 -0.1397)
							(mid 0.381 0)
							(end 0.2413 0.1397)
						)
						(xy -0.381 0.1397) (xy -0.381 -0.1397)
					)
					(width 0)
					(fill yes)
				)
			)
		)
		(pad "5" smd custom
			(at -2.8321 -0.249936 90)
			(size 0.06985 0.06985)
			(layers "F.Cu" "F.Mask" "F.Paste")
			(net "AGND_PVPP_DEF")
			(options
				(clearance outline)
				(anchor circle)
			)
			(primitives
				(gr_poly
					(pts
						(arc
							(start 0.2413 -0.1397)
							(mid 0.381 0)
							(end 0.2413 0.1397)
						)
						(xy -0.381 0.1397) (xy -0.381 -0.1397)
					)
					(width 0)
					(fill yes)
				)
			)
		)
		(pad "6" smd custom
			(at -2.8321 0.249936 90)
			(size 0.06985 0.06985)
			(layers "F.Cu" "F.Mask" "F.Paste")
			(net "AGND_PVPP_DEF")
			(options
				(clearance outline)
				(anchor circle)
			)
			(primitives
				(gr_poly
					(pts
						(arc
							(start 0.2413 -0.1397)
							(mid 0.381 0)
							(end 0.2413 0.1397)
						)
						(xy -0.381 0.1397) (xy -0.381 -0.1397)
					)
					(width 0)
					(fill yes)
				)
			)
		)
		(pad "7" smd custom
			(at -2.8321 0.750062 90)
			(size 0.06985 0.06985)
			(layers "F.Cu" "F.Mask" "F.Paste")
			(net "PWRGD_PVPP_DEF_R")
			(options
				(clearance outline)
				(anchor circle)
			)
			(primitives
				(gr_poly
					(pts
						(arc
							(start 0.2413 -0.1397)
							(mid 0.381 0)
							(end 0.2413 0.1397)
						)
						(xy -0.381 0.1397) (xy -0.381 -0.1397)
					)
					(width 0)
					(fill yes)
				)
			)
		)
		(pad "8" smd custom
			(at -2.8321 1.249934 90)
			(size 0.06985 0.06985)
			(layers "F.Cu" "F.Mask" "F.Paste")
			(net "VR_FET_SW_P12V_STBY_PVPP_DEF")
			(options
				(clearance outline)
				(anchor circle)
			)
			(primitives
				(gr_poly
					(pts
						(arc
							(start 0.2413 -0.1397)
							(mid 0.381 0)
							(end 0.2413 0.1397)
						)
						(xy -0.381 0.1397) (xy -0.381 -0.1397)
					)
					(width 0)
					(fill yes)
				)
			)
		)
		(pad "9" smd custom
			(at -2.8321 1.75006 90)
			(size 0.06985 0.06985)
			(layers "F.Cu" "F.Mask" "F.Paste")
			(net "VR_FET_SW_P12V_STBY_PVPP_DEF")
			(options
				(clearance outline)
				(anchor circle)
			)
			(primitives
				(gr_poly
					(pts
						(arc
							(start 0.2413 -0.1397)
							(mid 0.381 0)
							(end 0.2413 0.1397)
						)
						(xy -0.381 0.1397) (xy -0.381 -0.1397)
					)
					(width 0)
					(fill yes)
				)
			)
		)
		(pad "10" smd custom
			(at -2.8321 2.249932 90)
			(size 0.06985 0.06985)
			(layers "F.Cu" "F.Mask" "F.Paste")
			(net "VR_FET_SW_P12V_STBY_PVPP_DEF")
			(options
				(clearance outline)
				(anchor circle)
			)
			(primitives
				(gr_poly
					(pts
						(arc
							(start 0.2413 -0.1397)
							(mid 0.381 0)
							(end 0.2413 0.1397)
						)
						(xy -0.381 0.1397) (xy -0.381 -0.1397)
					)
					(width 0)
					(fill yes)
				)
			)
		)
		(pad "11" smd custom
			(at -2.249932 2.8321 90)
			(size 0.06985 0.06985)
			(layers "F.Cu" "F.Mask" "F.Paste")
			(net "VR_FET_SW_P12V_STBY_PVPP_DEF")
			(options
				(clearance outline)
				(anchor circle)
			)
			(primitives
				(gr_poly
					(pts
						(arc
							(start -0.1397 -0.2413)
							(mid 0 -0.381)
							(end 0.1397 -0.2413)
						)
						(xy 0.1397 0.381) (xy -0.1397 0.381)
					)
					(width 0)
					(fill yes)
				)
			)
		)
		(pad "12" smd custom
			(at -1.75006 2.8321 90)
			(size 0.06985 0.06985)
			(layers "F.Cu" "F.Mask" "F.Paste")
			(net "VR_FET_SW_P12V_STBY_PVPP_DEF")
			(options
				(clearance outline)
				(anchor circle)
			)
			(primitives
				(gr_poly
					(pts
						(arc
							(start -0.1397 -0.2413)
							(mid 0 -0.381)
							(end 0.1397 -0.2413)
						)
						(xy 0.1397 0.381) (xy -0.1397 0.381)
					)
					(width 0)
					(fill yes)
				)
			)
		)
		(pad "13" smd custom
			(at -1.249934 2.8321 90)
			(size 0.06985 0.06985)
			(layers "F.Cu" "F.Mask" "F.Paste")
			(net "VR_FET_SW_P12V_STBY_PVPP_DEF")
			(options
				(clearance outline)
				(anchor circle)
			)
			(primitives
				(gr_poly
					(pts
						(arc
							(start -0.1397 -0.2413)
							(mid 0 -0.381)
							(end 0.1397 -0.2413)
						)
						(xy 0.1397 0.381) (xy -0.1397 0.381)
					)
					(width 0)
					(fill yes)
				)
			)
		)
		(pad "14" smd custom
			(at -0.750062 2.8321 90)
			(size 0.06985 0.06985)
			(layers "F.Cu" "F.Mask" "F.Paste")
			(net "VR_FET_SW_P12V_STBY_PVPP_DEF")
			(options
				(clearance outline)
				(anchor circle)
			)
			(primitives
				(gr_poly
					(pts
						(arc
							(start -0.1397 -0.2413)
							(mid 0 -0.381)
							(end 0.1397 -0.2413)
						)
						(xy 0.1397 0.381) (xy -0.1397 0.381)
					)
					(width 0)
					(fill yes)
				)
			)
		)
		(pad "15" smd custom
			(at -0.249936 2.8321 90)
			(size 0.06985 0.06985)
			(layers "F.Cu" "F.Mask" "F.Paste")
			(net "VR_PVPP_DEF_PHASE")
			(options
				(clearance outline)
				(anchor circle)
			)
			(primitives
				(gr_poly
					(pts
						(arc
							(start -0.1397 -0.2413)
							(mid 0 -0.381)
							(end 0.1397 -0.2413)
						)
						(xy 0.1397 0.381) (xy -0.1397 0.381)
					)
					(width 0)
					(fill yes)
				)
			)
		)
		(pad "16" smd custom
			(at 0.249936 2.8321 90)
			(size 0.06985 0.06985)
			(layers "F.Cu" "F.Mask" "F.Paste")
			(net "GND")
			(options
				(clearance outline)
				(anchor circle)
			)
			(primitives
				(gr_poly
					(pts
						(arc
							(start -0.1397 -0.2413)
							(mid 0 -0.381)
							(end 0.1397 -0.2413)
						)
						(xy 0.1397 0.381) (xy -0.1397 0.381)
					)
					(width 0)
					(fill yes)
				)
			)
		)
		(pad "17" smd custom
			(at 0.750062 2.8321 90)
			(size 0.06985 0.06985)
			(layers "F.Cu" "F.Mask" "F.Paste")
			(net "GND")
			(options
				(clearance outline)
				(anchor circle)
			)
			(primitives
				(gr_poly
					(pts
						(arc
							(start -0.1397 -0.2413)
							(mid 0 -0.381)
							(end 0.1397 -0.2413)
						)
						(xy 0.1397 0.381) (xy -0.1397 0.381)
					)
					(width 0)
					(fill yes)
				)
			)
		)
	)
)
